FILE_TYPE = MACRO_DRAWING;
SET COLOR_WIRE YELLOW;
SET COLOR_PROP ORANGE;
SET COLOR_DOT WHITE;
SET COLOR_ARC YELLOW;
SET COLOR_BODY GREEN;
SET COLOR_NOTE PURPLE;
SET PROP_DISPLAY VALUE;
SET PAGE_NUMBER P203;
FORCEADD QUANTA_TITLE_BLOCK_C..1
(0 0);
FORCEPROP 1 LAST CUSTOM_TXT_CDS <NAME_2>
J 0
(-3175 50);
FORCEPROP 1 LAST CUSTOM_TXT_CDS <NAME_1>
J 0
(-3175 175);
FORCEPROP 1 LAST CUSTOM_TXT_CDS <Q_NUMBER>
J 0
(-1403 103);
DISPLAY 1.212766 (-1403 103);
FORCEPROP 1 LAST CUSTOM_TXT_CDS <Q_PROJ>
J 0
(-2382 102);
DISPLAY 1.212766 (-2382 102);
FORCEPROP 1 LAST CUSTOM_TXT_CDS <Q_REV>
J 0
(-184 103);
DISPLAY 1.212766 (-184 103);
FORCEPROP 1 LAST CUSTOM_TXT_CDS <CON_LAST_MODIFIED>
J 0
(-1885 15);
DISPLAY 0.978723 (-1885 15);
FORCEPROP 1 LAST CUSTOM_TXT_CDS <CON_PAGE_NUM> OF <CON_TOTAL_PAGES>
J 0
(-446 18);
DISPLAY 0.978723 (-446 18);
FORCEPROP 1 LAST Q_TITLE Blank
J 0
(-9366 26);
DISPLAY 2.446809 (-9366 26);
PAINT GREEN (-9366 26);
FORCEPROP 1 LAST Q_DEPT BU9
J 1
(-3763 49);
DISPLAY 1.957447 (-3763 49);
PAINT GREEN (-3763 49);
FORCEPROP 0 LAST CDS_CON_LAST_MODIFIED Wed Jul 21 15:11:14 2021
J 0
(-1885 15);
DISPLAY INVISIBLE (-1885 15);
FORCEPROP 2 LAST PAGE_BORDER TRUE
J 0
(-7890 5250);
DISPLAY 0.638298 (-7890 5250);
PAINT PINK (-7890 5250);
DISPLAY INVISIBLE (-7890 5250);
FORCEPROP 1 LAST CDS_LMAN_SYM_OUTLINE -9475,6775,100,-125
J 0
(0 0);
DISPLAY 0.468085 (0 0);
PAINT GREEN (0 0);
DISPLAY INVISIBLE (0 0);
FORCEPROP 2 LAST CDS_LIB pure_quanta
J 0
(0 0);
DISPLAY INVISIBLE (0 0);
FORCEPROP 1 LAST COMMENT_BODY TRUE
J 0
(12 -13);
DISPLAY 0.978723 (12 -13);
PAINT GREEN (12 -13);
DISPLAY INVISIBLE (12 -13);
FORCEPROP 2 LAST CUSTOM_TXT_CDS <XR_PAGE_TITLE>
J 0
(-7890 5250);
DISPLAY 0.638298 (-7890 5250);
PAINT PINK (-7890 5250);
DISPLAY INVISIBLE (-7890 5250);
FORCEPROP 2 LAST CDS_XR_PAGE_TITLE CR-204 : @T6G_MB_LIB.T6G(SCH_1):PAGE204
J 0
(-7890 5250);
DISPLAY 0.638298 (-7890 5250);
PAINT PINK (-7890 5250);
DISPLAY INVISIBLE (-7890 5250);
QUIT
